(kicad_pcb
	(version 20260206)
	(generator "pcbnew")
	(generator_version "10.0")
	(general
		(thickness 1.6)
		(legacy_teardrops no)
	)
	(paper "A4")
	(title_block
		(title "03242023_DA0F0TMBIJ0_F0T_Motherboard_J_brd_V01_OCP.brd")
		(comment 1 "Grand Teton / footprints 3160-3164 of 6105")
	)
	(layers
		(0 "F.Cu" signal "TOP")
		(4 "In1.Cu" signal "GND")
		(6 "In2.Cu" signal "IN1")
		(8 "In3.Cu" signal "GND1")
		(10 "In4.Cu" signal "IN2")
		(12 "In5.Cu" signal "GND2")
		(14 "In6.Cu" signal "IN3")
		(16 "In7.Cu" signal "GND3")
		(18 "In8.Cu" signal "VCC")
		(20 "In9.Cu" signal "VCC1")
		(22 "In10.Cu" signal "GND4")
		(24 "In11.Cu" signal "IN4")
		(26 "In12.Cu" signal "GND5")
		(28 "In13.Cu" signal "IN5")
		(30 "In14.Cu" signal "GND6")
		(32 "In15.Cu" signal "IN6")
		(34 "In16.Cu" signal "GND7")
		(2 "B.Cu" signal "BOTTOM")
		(9 "F.Adhes" user "F.Adhesive")
		(11 "B.Adhes" user "B.Adhesive")
		(13 "F.Paste" user "Package Geometry/Pastemask Top")
		(15 "B.Paste" user "Package Geometry/Pastemask Bottom")
		(5 "F.SilkS" user "Ref Des/Silkscreen Top")
		(7 "B.SilkS" user "Ref Des/Silkscreen Bottom")
		(1 "F.Mask" user "Board Geometry/Soldermask Top")
		(3 "B.Mask" user "Board Geometry/Soldermask Bottom")
		(17 "Dwgs.User" user "User.Drawings")
		(19 "Cmts.User" user "User.Comments")
		(21 "Eco1.User" user "User.Eco1")
		(23 "Eco2.User" user "User.Eco2")
		(25 "Edge.Cuts" user "Board Geometry/Outline")
		(27 "Margin" user)
		(31 "F.CrtYd" user "Package Geometry/Place Bound Top")
		(29 "B.CrtYd" user "Package Geometry/Place Bound Bottom")
		(35 "F.Fab" user "Ref Des/Assembly Top")
		(33 "B.Fab" user "Ref Des/Assembly Bottom")
	)
	(footprint ""
		(layer "F.Cu")
		(at 190.41364 -70.185788)
		(property "Reference" "PR3947"
			(at 0 0 0)
			(layer "F.SilkS")
			(hide yes)
			(effects
				(font
					(size 1.27 1.27)
				)
			)
		)
		(property "Value" ""
			(at 0 0 0)
			(layer "F.Fab")
			(effects
				(font
					(size 1.27 1.27)
				)
			)
		)
		(duplicate_pad_numbers_are_jumpers no)
		(fp_line
			(start -0.7874 -0.4064)
			(end 0.7874 -0.4064)
			(stroke
				(width 0.1524)
				(type default)
			)
			(layer "F.SilkS")
		)
		(fp_line
			(start -0.7874 0.4064)
			(end -0.7874 -0.4064)
			(stroke
				(width 0.1524)
				(type default)
			)
			(layer "F.SilkS")
		)
		(fp_line
			(start 0.7874 -0.4064)
			(end 0.7874 0.4064)
			(stroke
				(width 0.1524)
				(type default)
			)
			(layer "F.SilkS")
		)
		(fp_line
			(start 0.7874 0.4064)
			(end -0.7874 0.4064)
			(stroke
				(width 0.1524)
				(type default)
			)
			(layer "F.SilkS")
		)
		(fp_line
			(start -0.67945 -0.305054)
			(end -0.12065 -0.305054)
			(stroke
				(width 0.1)
				(type default)
			)
			(layer "F.Fab")
		)
		(fp_line
			(start -0.67945 0.3048)
			(end -0.67945 -0.305054)
			(stroke
				(width 0.1)
				(type default)
			)
			(layer "F.Fab")
		)
		(fp_line
			(start -0.12065 -0.305054)
			(end -0.12065 -0.2794)
			(stroke
				(width 0.1)
				(type default)
			)
			(layer "F.Fab")
		)
		(fp_line
			(start -0.12065 -0.2794)
			(end 0.12065 -0.2794)
			(stroke
				(width 0.1)
				(type default)
			)
			(layer "F.Fab")
		)
		(fp_line
			(start -0.12065 0.2794)
			(end -0.12065 0.3048)
			(stroke
				(width 0.1)
				(type default)
			)
			(layer "F.Fab")
		)
		(fp_line
			(start -0.12065 0.3048)
			(end -0.67945 0.3048)
			(stroke
				(width 0.1)
				(type default)
			)
			(layer "F.Fab")
		)
		(fp_line
			(start 0.120396 0.2794)
			(end -0.12065 0.2794)
			(stroke
				(width 0.1)
				(type default)
			)
			(layer "F.Fab")
		)
		(fp_line
			(start 0.120396 0.3048)
			(end 0.120396 0.2794)
			(stroke
				(width 0.1)
				(type default)
			)
			(layer "F.Fab")
		)
		(fp_line
			(start 0.12065 -0.3048)
			(end 0.67945 -0.3048)
			(stroke
				(width 0.1)
				(type default)
			)
			(layer "F.Fab")
		)
		(fp_line
			(start 0.12065 -0.2794)
			(end 0.12065 -0.3048)
			(stroke
				(width 0.1)
				(type default)
			)
			(layer "F.Fab")
		)
		(fp_line
			(start 0.67945 -0.3048)
			(end 0.67945 0.3048)
			(stroke
				(width 0.1)
				(type default)
			)
			(layer "F.Fab")
		)
		(fp_line
			(start 0.67945 0.3048)
			(end 0.120396 0.3048)
			(stroke
				(width 0.1)
				(type default)
			)
			(layer "F.Fab")
		)
		(pad "1" smd circle
			(at -0.40005 0)
			(size 0 0)
			(layers "F.Cu" "F.Mask" "F.Paste")
			(net "GND")
		)
		(pad "2" smd circle
			(at 0.40005 0)
			(size 0 0)
			(layers "F.Cu" "F.Mask" "F.Paste")
			(net "P3V3_E1S_ILIMIT_0")
		)
	)
	(footprint ""
		(layer "F.Cu")
		(at 83.55711 -59.242706 90)
		(property "Reference" "PR3822"
			(at 0 0 90)
			(layer "F.SilkS")
			(hide yes)
			(effects
				(font
					(size 1.27 1.27)
				)
			)
		)
		(property "Value" ""
			(at 0 0 90)
			(layer "F.Fab")
			(effects
				(font
					(size 1.27 1.27)
				)
			)
		)
		(duplicate_pad_numbers_are_jumpers no)
		(fp_line
			(start 0.7874 -0.4064)
			(end 0.7874 0.4064)
			(stroke
				(width 0.1524)
				(type default)
			)
			(layer "F.SilkS")
		)
		(fp_line
			(start -0.7874 -0.4064)
			(end 0.7874 -0.4064)
			(stroke
				(width 0.1524)
				(type default)
			)
			(layer "F.SilkS")
		)
		(fp_line
			(start 0.7874 0.4064)
			(end -0.7874 0.4064)
			(stroke
				(width 0.1524)
				(type default)
			)
			(layer "F.SilkS")
		)
		(fp_line
			(start -0.7874 0.4064)
			(end -0.7874 -0.4064)
			(stroke
				(width 0.1524)
				(type default)
			)
			(layer "F.SilkS")
		)
		(fp_line
			(start -0.12065 -0.305054)
			(end -0.12065 -0.2794)
			(stroke
				(width 0.1)
				(type default)
			)
			(layer "F.Fab")
		)
		(fp_line
			(start -0.67945 -0.305054)
			(end -0.12065 -0.305054)
			(stroke
				(width 0.1)
				(type default)
			)
			(layer "F.Fab")
		)
		(fp_line
			(start 0.67945 -0.3048)
			(end 0.67945 0.3048)
			(stroke
				(width 0.1)
				(type default)
			)
			(layer "F.Fab")
		)
		(fp_line
			(start 0.12065 -0.3048)
			(end 0.67945 -0.3048)
			(stroke
				(width 0.1)
				(type default)
			)
			(layer "F.Fab")
		)
		(fp_line
			(start 0.12065 -0.2794)
			(end 0.12065 -0.3048)
			(stroke
				(width 0.1)
				(type default)
			)
			(layer "F.Fab")
		)
		(fp_line
			(start -0.12065 -0.2794)
			(end 0.12065 -0.2794)
			(stroke
				(width 0.1)
				(type default)
			)
			(layer "F.Fab")
		)
		(fp_line
			(start 0.120396 0.2794)
			(end -0.12065 0.2794)
			(stroke
				(width 0.1)
				(type default)
			)
			(layer "F.Fab")
		)
		(fp_line
			(start -0.12065 0.2794)
			(end -0.12065 0.3048)
			(stroke
				(width 0.1)
				(type default)
			)
			(layer "F.Fab")
		)
		(fp_line
			(start 0.67945 0.3048)
			(end 0.120396 0.3048)
			(stroke
				(width 0.1)
				(type default)
			)
			(layer "F.Fab")
		)
		(fp_line
			(start 0.120396 0.3048)
			(end 0.120396 0.2794)
			(stroke
				(width 0.1)
				(type default)
			)
			(layer "F.Fab")
		)
		(fp_line
			(start -0.12065 0.3048)
			(end -0.67945 0.3048)
			(stroke
				(width 0.1)
				(type default)
			)
			(layer "F.Fab")
		)
		(fp_line
			(start -0.67945 0.3048)
			(end -0.67945 -0.305054)
			(stroke
				(width 0.1)
				(type default)
			)
			(layer "F.Fab")
		)
		(pad "1" smd circle
			(at -0.40005 0 90)
			(size 0 0)
			(layers "F.Cu" "F.Mask" "F.Paste")
			(net "P3V3_OCP_CB_2")
		)
		(pad "2" smd circle
			(at 0.40005 0 90)
			(size 0 0)
			(layers "F.Cu" "F.Mask" "F.Paste")
			(net "GND")
		)
	)
	(footprint ""
		(layer "F.Cu")
		(at 252.83287 -41.039542 -90)
		(property "Reference" "PU294"
			(at -0.130556 -1.349502 0)
			(unlocked yes)
			(layer "F.SilkS")
			(effects
				(font
					(size 0.7874 0.5842)
					(thickness 0.1524)
				)
				(justify left)
			)
		)
		(property "Value" ""
			(at 0 0 270)
			(layer "F.Fab")
			(effects
				(font
					(size 1.27 1.27)
				)
			)
		)
		(duplicate_pad_numbers_are_jumpers no)
		(fp_line
			(start -1.774952 1.039876)
			(end 1.774952 1.039876)
			(stroke
				(width 0.1524)
				(type default)
			)
			(layer "F.SilkS")
		)
		(fp_line
			(start 1.774952 1.039876)
			(end 1.774952 -1.039876)
			(stroke
				(width 0.1524)
				(type default)
			)
			(layer "F.SilkS")
		)
		(fp_line
			(start -1.774952 -1.039876)
			(end -1.774952 1.039876)
			(stroke
				(width 0.1524)
				(type default)
			)
			(layer "F.SilkS")
		)
		(fp_line
			(start 1.774952 -1.039876)
			(end -1.774952 -1.039876)
			(stroke
				(width 0.1524)
				(type default)
			)
			(layer "F.SilkS")
		)
		(fp_poly
			(pts
				(xy -1.769872 -1.039876) (xy -1.769872 -0.249936) (xy -2.531872 -0.249936) (xy -2.531872 -1.801876)
				(xy -0.999998 -1.801876) (xy -0.999998 -1.039876)
			)
			(stroke
				(width 0)
				(type default)
			)
			(fill yes)
			(layer "F.SilkS")
		)
		(fp_line
			(start -1.769872 1.039876)
			(end 1.769872 1.039876)
			(stroke
				(width 0.1)
				(type default)
			)
			(layer "F.Fab")
		)
		(fp_line
			(start 1.769872 1.039876)
			(end 1.769872 -1.039876)
			(stroke
				(width 0.1)
				(type default)
			)
			(layer "F.Fab")
		)
		(fp_line
			(start -1.769872 -1.039876)
			(end -1.769872 1.039876)
			(stroke
				(width 0.1)
				(type default)
			)
			(layer "F.Fab")
		)
		(fp_line
			(start 1.769872 -1.039876)
			(end -1.769872 -1.039876)
			(stroke
				(width 0.1)
				(type default)
			)
			(layer "F.Fab")
		)
		(fp_poly
			(pts
				(xy -1.769872 -1.039876) (xy -0.999998 -1.039876) (xy -0.999998 -1.801876) (xy -2.531872 -1.801876)
				(xy -2.531872 -0.249936) (xy -1.769872 -0.249936)
			)
			(stroke
				(width 0)
				(type default)
			)
			(fill yes)
			(layer "F.Fab")
		)
		(pad "A1" smd circle
			(at -1.500124 -0.750062 270)
			(size 0.2286 0.2286)
			(layers "F.Cu" "F.Mask" "F.Paste")
			(net "P12V_E1S_SENSE_0")
		)
		(pad "A2" smd circle
			(at -0.999998 -0.750062 270)
			(size 0.2286 0.2286)
			(layers "F.Cu" "F.Mask" "F.Paste")
			(net "P12V_E1S_VCC_0")
		)
		(pad "A3" smd circle
			(at -0.499872 -0.750062 270)
			(size 0.2286 0.2286)
			(layers "F.Cu" "F.Mask" "F.Paste")
			(net "P12V_AUX")
		)
		(pad "A4" smd circle
			(at 0 -0.750062 270)
			(size 0.2286 0.2286)
			(layers "F.Cu" "F.Mask" "F.Paste")
			(net "P12V_E1S_0")
		)
		(pad "A5" smd circle
			(at 0.499872 -0.750062 270)
			(size 0.2286 0.2286)
			(layers "F.Cu" "F.Mask" "F.Paste")
			(net "P12V_AUX")
		)
		(pad "A6" smd circle
			(at 0.999998 -0.750062 270)
			(size 0.2286 0.2286)
			(layers "F.Cu" "F.Mask" "F.Paste")
			(net "P12V_E1S_GATE_0")
		)
		(pad "A7" smd circle
			(at 1.500124 -0.750062 270)
			(size 0.2286 0.2286)
			(layers "F.Cu" "F.Mask" "F.Paste")
			(net "GND")
		)
		(pad "B1" smd circle
			(at -1.500124 -0.249936 270)
			(size 0.2286 0.2286)
			(layers "F.Cu" "F.Mask" "F.Paste")
			(net "P12V_E1S_CB_0")
		)
		(pad "B2" smd circle
			(at -0.999998 -0.249936 270)
			(size 0.2286 0.2286)
			(layers "F.Cu" "F.Mask" "F.Paste")
			(net "GND")
		)
		(pad "B3" smd circle
			(at -0.499872 -0.249936 270)
			(size 0.2286 0.2286)
			(layers "F.Cu" "F.Mask" "F.Paste")
			(net "P12V_AUX")
		)
		(pad "B4" smd circle
			(at 0 -0.249936 270)
			(size 0.2286 0.2286)
			(layers "F.Cu" "F.Mask" "F.Paste")
			(net "P12V_E1S_0")
		)
		(pad "B5" smd circle
			(at 0.499872 -0.249936 270)
			(size 0.2286 0.2286)
			(layers "F.Cu" "F.Mask" "F.Paste")
			(net "P12V_AUX")
		)
		(pad "B6" smd circle
			(at 0.999998 -0.249936 270)
			(size 0.2286 0.2286)
			(layers "F.Cu" "F.Mask" "F.Paste")
			(net "P12V_E1S_0")
		)
		(pad "B7" smd circle
			(at 1.500124 -0.249936 270)
			(size 0.2286 0.2286)
			(layers "F.Cu" "F.Mask" "F.Paste")
			(net "GND")
		)
		(pad "C1" smd circle
			(at -1.500124 0.249936 270)
			(size 0.2286 0.2286)
			(layers "F.Cu" "F.Mask" "F.Paste")
			(net "GND")
		)
		(pad "C2" smd circle
			(at -0.999998 0.249936 270)
			(size 0.2286 0.2286)
			(layers "F.Cu" "F.Mask" "F.Paste")
			(net "GND")
		)
		(pad "C3" smd circle
			(at -0.499872 0.249936 270)
			(size 0.2286 0.2286)
			(layers "F.Cu" "F.Mask" "F.Paste")
			(net "P12V_AUX")
		)
		(pad "C4" smd circle
			(at 0 0.249936 270)
			(size 0.2286 0.2286)
			(layers "F.Cu" "F.Mask" "F.Paste")
			(net "P12V_E1S_0")
		)
		(pad "C5" smd circle
			(at 0.499872 0.249936 270)
			(size 0.2286 0.2286)
			(layers "F.Cu" "F.Mask" "F.Paste")
			(net "P12V_AUX")
		)
		(pad "C6" smd circle
			(at 0.999998 0.249936 270)
			(size 0.2286 0.2286)
			(layers "F.Cu" "F.Mask" "F.Paste")
			(net "P12V_E1S_0")
		)
		(pad "C7" smd circle
			(at 1.500124 0.249936 270)
			(size 0.2286 0.2286)
			(layers "F.Cu" "F.Mask" "F.Paste")
			(net "P12V_E1S_FAULT_0")
		)
		(pad "D1" smd circle
			(at -1.500124 0.750062 270)
			(size 0.2286 0.2286)
			(layers "F.Cu" "F.Mask" "F.Paste")
			(net "P12V_E1S_REG_0")
		)
		(pad "D2" smd circle
			(at -0.999998 0.750062 270)
			(size 0.2286 0.2286)
			(layers "F.Cu" "F.Mask" "F.Paste")
			(net "P12V_E1S_UV_0")
		)
		(pad "D3" smd circle
			(at -0.499872 0.750062 270)
			(size 0.2286 0.2286)
			(layers "F.Cu" "F.Mask" "F.Paste")
			(net "P12V_E1S_OV_0")
		)
		(pad "D4" smd circle
			(at 0 0.750062 270)
			(size 0.2286 0.2286)
			(layers "F.Cu" "F.Mask" "F.Paste")
			(net "P12V_E1S_0")
		)
		(pad "D5" smd circle
			(at 0.499872 0.750062 270)
			(size 0.2286 0.2286)
			(layers "F.Cu" "F.Mask" "F.Paste")
			(net "P12V_AUX")
		)
		(pad "D6" smd circle
			(at 0.999998 0.750062 270)
			(size 0.2286 0.2286)
			(layers "F.Cu" "F.Mask" "F.Paste")
			(net "P12V_E1S_0")
		)
		(pad "D7" smd circle
			(at 1.500124 0.750062 270)
			(size 0.2286 0.2286)
			(layers "F.Cu" "F.Mask" "F.Paste")
			(net "P12V_E1S_PWRGD_0")
		)
	)
	(footprint ""
		(layer "F.Cu")
		(at 176.078388 -417.745418)
		(property "Reference" "C1975"
			(at 0 0 0)
			(layer "F.SilkS")
			(hide yes)
			(effects
				(font
					(size 1.27 1.27)
				)
			)
		)
		(property "Value" ""
			(at 0 0 0)
			(layer "F.Fab")
			(effects
				(font
					(size 1.27 1.27)
				)
			)
		)
		(duplicate_pad_numbers_are_jumpers no)
		(fp_line
			(start -0.7874 -0.4064)
			(end 0.7874 -0.4064)
			(stroke
				(width 0.1524)
				(type default)
			)
			(layer "F.SilkS")
		)
		(fp_line
			(start -0.7874 0.4064)
			(end -0.7874 -0.4064)
			(stroke
				(width 0.1524)
				(type default)
			)
			(layer "F.SilkS")
		)
		(fp_line
			(start 0.7874 -0.4064)
			(end 0.7874 0.4064)
			(stroke
				(width 0.1524)
				(type default)
			)
			(layer "F.SilkS")
		)
		(fp_line
			(start 0.7874 0.4064)
			(end -0.7874 0.4064)
			(stroke
				(width 0.1524)
				(type default)
			)
			(layer "F.SilkS")
		)
		(fp_line
			(start -0.67945 -0.305054)
			(end -0.12065 -0.305054)
			(stroke
				(width 0.1)
				(type default)
			)
			(layer "F.Fab")
		)
		(fp_line
			(start -0.67945 0.3048)
			(end -0.67945 -0.305054)
			(stroke
				(width 0.1)
				(type default)
			)
			(layer "F.Fab")
		)
		(fp_line
			(start -0.12065 -0.305054)
			(end -0.12065 -0.2794)
			(stroke
				(width 0.1)
				(type default)
			)
			(layer "F.Fab")
		)
		(fp_line
			(start -0.12065 -0.2794)
			(end 0.12065 -0.2794)
			(stroke
				(width 0.1)
				(type default)
			)
			(layer "F.Fab")
		)
		(fp_line
			(start -0.12065 0.2794)
			(end -0.12065 0.3048)
			(stroke
				(width 0.1)
				(type default)
			)
			(layer "F.Fab")
		)
		(fp_line
			(start -0.12065 0.3048)
			(end -0.67945 0.3048)
			(stroke
				(width 0.1)
				(type default)
			)
			(layer "F.Fab")
		)
		(fp_line
			(start 0.120396 0.2794)
			(end -0.12065 0.2794)
			(stroke
				(width 0.1)
				(type default)
			)
			(layer "F.Fab")
		)
		(fp_line
			(start 0.120396 0.3048)
			(end 0.120396 0.2794)
			(stroke
				(width 0.1)
				(type default)
			)
			(layer "F.Fab")
		)
		(fp_line
			(start 0.12065 -0.3048)
			(end 0.67945 -0.3048)
			(stroke
				(width 0.1)
				(type default)
			)
			(layer "F.Fab")
		)
		(fp_line
			(start 0.12065 -0.2794)
			(end 0.12065 -0.3048)
			(stroke
				(width 0.1)
				(type default)
			)
			(layer "F.Fab")
		)
		(fp_line
			(start 0.67945 -0.3048)
			(end 0.67945 0.3048)
			(stroke
				(width 0.1)
				(type default)
			)
			(layer "F.Fab")
		)
		(fp_line
			(start 0.67945 0.3048)
			(end 0.120396 0.3048)
			(stroke
				(width 0.1)
				(type default)
			)
			(layer "F.Fab")
		)
		(pad "1" smd circle
			(at -0.40005 0)
			(size 0 0)
			(layers "F.Cu" "F.Mask" "F.Paste")
			(net "GPU_HMC_PRSNT_ISO_N")
		)
		(pad "2" smd circle
			(at 0.40005 0)
			(size 0 0)
			(layers "F.Cu" "F.Mask" "F.Paste")
			(net "GND")
		)
	)
	(footprint ""
		(layer "F.Cu")
		(at 453.054212 -24.619458 180)
		(property "Reference" "PC2088"
			(at 0 0 180)
			(layer "F.SilkS")
			(hide yes)
			(effects
				(font
					(size 1.27 1.27)
				)
			)
		)
		(property "Value" ""
			(at 0 0 180)
			(layer "F.Fab")
			(effects
				(font
					(size 1.27 1.27)
				)
			)
		)
		(duplicate_pad_numbers_are_jumpers no)
		(fp_line
			(start 0.7874 0.4064)
			(end -0.7874 0.4064)
			(stroke
				(width 0.1524)
				(type default)
			)
			(layer "F.SilkS")
		)
		(fp_line
			(start 0.7874 -0.4064)
			(end 0.7874 0.4064)
			(stroke
				(width 0.1524)
				(type default)
			)
			(layer "F.SilkS")
		)
		(fp_line
			(start -0.7874 0.4064)
			(end -0.7874 -0.4064)
			(stroke
				(width 0.1524)
				(type default)
			)
			(layer "F.SilkS")
		)
		(fp_line
			(start -0.7874 -0.4064)
			(end 0.7874 -0.4064)
			(stroke
				(width 0.1524)
				(type default)
			)
			(layer "F.SilkS")
		)
		(fp_line
			(start 0.67945 0.3048)
			(end 0.120396 0.3048)
			(stroke
				(width 0.1)
				(type default)
			)
			(layer "F.Fab")
		)
		(fp_line
			(start 0.67945 -0.3048)
			(end 0.67945 0.3048)
			(stroke
				(width 0.1)
				(type default)
			)
			(layer "F.Fab")
		)
		(fp_line
			(start 0.12065 -0.2794)
			(end 0.12065 -0.3048)
			(stroke
				(width 0.1)
				(type default)
			)
			(layer "F.Fab")
		)
		(fp_line
			(start 0.12065 -0.3048)
			(end 0.67945 -0.3048)
			(stroke
				(width 0.1)
				(type default)
			)
			(layer "F.Fab")
		)
		(fp_line
			(start 0.120396 0.3048)
			(end 0.120396 0.2794)
			(stroke
				(width 0.1)
				(type default)
			)
			(layer "F.Fab")
		)
		(fp_line
			(start 0.120396 0.2794)
			(end -0.12065 0.2794)
			(stroke
				(width 0.1)
				(type default)
			)
			(layer "F.Fab")
		)
		(fp_line
			(start -0.12065 0.3048)
			(end -0.67945 0.3048)
			(stroke
				(width 0.1)
				(type default)
			)
			(layer "F.Fab")
		)
		(fp_line
			(start -0.12065 0.2794)
			(end -0.12065 0.3048)
			(stroke
				(width 0.1)
				(type default)
			)
			(layer "F.Fab")
		)
		(fp_line
			(start -0.12065 -0.2794)
			(end 0.12065 -0.2794)
			(stroke
				(width 0.1)
				(type default)
			)
			(layer "F.Fab")
		)
		(fp_line
			(start -0.12065 -0.305054)
			(end -0.12065 -0.2794)
			(stroke
				(width 0.1)
				(type default)
			)
			(layer "F.Fab")
		)
		(fp_line
			(start -0.67945 0.3048)
			(end -0.67945 -0.305054)
			(stroke
				(width 0.1)
				(type default)
			)
			(layer "F.Fab")
		)
		(fp_line
			(start -0.67945 -0.305054)
			(end -0.12065 -0.305054)
			(stroke
				(width 0.1)
				(type default)
			)
			(layer "F.Fab")
		)
		(pad "1" smd circle
			(at -0.40005 0 180)
			(size 0 0)
			(layers "F.Cu" "F.Mask" "F.Paste")
			(net "P12V_OCP_SFF")
		)
		(pad "2" smd circle
			(at 0.40005 0 180)
			(size 0 0)
			(layers "F.Cu" "F.Mask" "F.Paste")
			(net "P12V_OCP_GATE_1")
		)
	)
)
